# S9S_MB_2U (Grand Teton) — schematic netlist excerpt (pin names and nets, part order shuffled) for the footprints in the layout excerpt that follows; sources: Cadence DE-HDL packaged netlist, KiCad conversion of 03242023_DA0F0TMBIJ0_F0T_Motherboard_J_brd_V01_OCP.brd

R3154  Q_RES  1K 1% CHIP  pkg 0402LF  page 164 : A = PD_SMB_OCP2_HP_ADD0 ; B = GND
C1829  Q_CAP  22UF 16V 20% X6S  pkg C0805  page 159 : A = P12V_OCP_V3_2 ; B = GND
R3186  Q_RES  33.2 1% CHIP  pkg 0402LF  page 161 : A = RST_OCP_V3_2_BUF_N ; B = RST_PERST0_OCP_V3_2_N

(kicad_pcb
	(version 20260206)
	(generator "pcbnew")
	(generator_version "10.0")
	(general
		(thickness 1.6)
		(legacy_teardrops no)
	)
	(paper "A4")
	(title_block
		(title "03242023_DA0F0TMBIJ0_F0T_Motherboard_J_brd_V01_OCP.brd")
		(comment 1 "Grand Teton / footprints 2295-2297 of 6105")
	)
	(layers
		(0 "F.Cu" signal "TOP")
		(4 "In1.Cu" signal "GND")
		(6 "In2.Cu" signal "IN1")
		(8 "In3.Cu" signal "GND1")
		(10 "In4.Cu" signal "IN2")
		(12 "In5.Cu" signal "GND2")
		(14 "In6.Cu" signal "IN3")
		(16 "In7.Cu" signal "GND3")
		(18 "In8.Cu" signal "VCC")
		(20 "In9.Cu" signal "VCC1")
		(22 "In10.Cu" signal "GND4")
		(24 "In11.Cu" signal "IN4")
		(26 "In12.Cu" signal "GND5")
		(28 "In13.Cu" signal "IN5")
		(30 "In14.Cu" signal "GND6")
		(32 "In15.Cu" signal "IN6")
		(34 "In16.Cu" signal "GND7")
		(2 "B.Cu" signal "BOTTOM")
		(9 "F.Adhes" user "F.Adhesive")
		(11 "B.Adhes" user "B.Adhesive")
		(13 "F.Paste" user "Package Geometry/Pastemask Top")
		(15 "B.Paste" user "Package Geometry/Pastemask Bottom")
		(5 "F.SilkS" user "Ref Des/Silkscreen Top")
		(7 "B.SilkS" user "Ref Des/Silkscreen Bottom")
		(1 "F.Mask" user "Board Geometry/Soldermask Top")
		(3 "B.Mask" user "Board Geometry/Soldermask Bottom")
		(17 "Dwgs.User" user "User.Drawings")
		(19 "Cmts.User" user "User.Comments")
		(21 "Eco1.User" user "User.Eco1")
		(23 "Eco2.User" user "User.Eco2")
		(25 "Edge.Cuts" user "Board Geometry/Outline")
		(27 "Margin" user)
		(31 "F.CrtYd" user "Package Geometry/Place Bound Top")
		(29 "B.CrtYd" user "Package Geometry/Place Bound Bottom")
		(35 "F.Fab" user "Ref Des/Assembly Top")
		(33 "B.Fab" user "Ref Des/Assembly Bottom")
	)
	(footprint ""
		(layer "F.Cu")
		(at 149.75078 -124.005848)
		(property "Reference" "R3154"
			(at 0 0 0)
			(layer "F.SilkS")
			(hide yes)
			(effects
				(font
					(size 1.27 1.27)
				)
			)
		)
		(property "Value" ""
			(at 0 0 0)
			(layer "F.Fab")
			(effects
				(font
					(size 1.27 1.27)
				)
			)
		)
		(duplicate_pad_numbers_are_jumpers no)
		(fp_line
			(start -0.7874 -0.4064)
			(end 0.7874 -0.4064)
			(stroke
				(width 0.1524)
				(type default)
			)
			(layer "F.SilkS")
		)
		(fp_line
			(start -0.7874 0.4064)
			(end -0.7874 -0.4064)
			(stroke
				(width 0.1524)
				(type default)
			)
			(layer "F.SilkS")
		)
		(fp_line
			(start 0.7874 -0.4064)
			(end 0.7874 0.4064)
			(stroke
				(width 0.1524)
				(type default)
			)
			(layer "F.SilkS")
		)
		(fp_line
			(start 0.7874 0.4064)
			(end -0.7874 0.4064)
			(stroke
				(width 0.1524)
				(type default)
			)
			(layer "F.SilkS")
		)
		(fp_line
			(start -0.67945 -0.305054)
			(end -0.12065 -0.305054)
			(stroke
				(width 0.1)
				(type default)
			)
			(layer "F.Fab")
		)
		(fp_line
			(start -0.67945 0.3048)
			(end -0.67945 -0.305054)
			(stroke
				(width 0.1)
				(type default)
			)
			(layer "F.Fab")
		)
		(fp_line
			(start -0.12065 -0.305054)
			(end -0.12065 -0.2794)
			(stroke
				(width 0.1)
				(type default)
			)
			(layer "F.Fab")
		)
		(fp_line
			(start -0.12065 -0.2794)
			(end 0.12065 -0.2794)
			(stroke
				(width 0.1)
				(type default)
			)
			(layer "F.Fab")
		)
		(fp_line
			(start -0.12065 0.2794)
			(end -0.12065 0.3048)
			(stroke
				(width 0.1)
				(type default)
			)
			(layer "F.Fab")
		)
		(fp_line
			(start -0.12065 0.3048)
			(end -0.67945 0.3048)
			(stroke
				(width 0.1)
				(type default)
			)
			(layer "F.Fab")
		)
		(fp_line
			(start 0.120396 0.2794)
			(end -0.12065 0.2794)
			(stroke
				(width 0.1)
				(type default)
			)
			(layer "F.Fab")
		)
		(fp_line
			(start 0.120396 0.3048)
			(end 0.120396 0.2794)
			(stroke
				(width 0.1)
				(type default)
			)
			(layer "F.Fab")
		)
		(fp_line
			(start 0.12065 -0.3048)
			(end 0.67945 -0.3048)
			(stroke
				(width 0.1)
				(type default)
			)
			(layer "F.Fab")
		)
		(fp_line
			(start 0.12065 -0.2794)
			(end 0.12065 -0.3048)
			(stroke
				(width 0.1)
				(type default)
			)
			(layer "F.Fab")
		)
		(fp_line
			(start 0.67945 -0.3048)
			(end 0.67945 0.3048)
			(stroke
				(width 0.1)
				(type default)
			)
			(layer "F.Fab")
		)
		(fp_line
			(start 0.67945 0.3048)
			(end 0.120396 0.3048)
			(stroke
				(width 0.1)
				(type default)
			)
			(layer "F.Fab")
		)
		(pad "1" smd circle
			(at -0.40005 0)
			(size 0 0)
			(layers "F.Cu" "F.Mask" "F.Paste")
			(net "PD_SMB_OCP2_HP_ADD0")
		)
		(pad "2" smd circle
			(at 0.40005 0)
			(size 0 0)
			(layers "F.Cu" "F.Mask" "F.Paste")
			(net "GND")
		)
	)
	(footprint ""
		(layer "F.Cu")
		(at 106.476038 -39.996364)
		(property "Reference" "R3186"
			(at 0 0 0)
			(layer "F.SilkS")
			(hide yes)
			(effects
				(font
					(size 1.27 1.27)
				)
			)
		)
		(property "Value" ""
			(at 0 0 0)
			(layer "F.Fab")
			(effects
				(font
					(size 1.27 1.27)
				)
			)
		)
		(duplicate_pad_numbers_are_jumpers no)
		(fp_line
			(start -0.7874 -0.4064)
			(end 0.7874 -0.4064)
			(stroke
				(width 0.1524)
				(type default)
			)
			(layer "F.SilkS")
		)
		(fp_line
			(start -0.7874 0.4064)
			(end -0.7874 -0.4064)
			(stroke
				(width 0.1524)
				(type default)
			)
			(layer "F.SilkS")
		)
		(fp_line
			(start 0.7874 -0.4064)
			(end 0.7874 0.4064)
			(stroke
				(width 0.1524)
				(type default)
			)
			(layer "F.SilkS")
		)
		(fp_line
			(start 0.7874 0.4064)
			(end -0.7874 0.4064)
			(stroke
				(width 0.1524)
				(type default)
			)
			(layer "F.SilkS")
		)
		(fp_line
			(start -0.67945 -0.305054)
			(end -0.12065 -0.305054)
			(stroke
				(width 0.1)
				(type default)
			)
			(layer "F.Fab")
		)
		(fp_line
			(start -0.67945 0.3048)
			(end -0.67945 -0.305054)
			(stroke
				(width 0.1)
				(type default)
			)
			(layer "F.Fab")
		)
		(fp_line
			(start -0.12065 -0.305054)
			(end -0.12065 -0.2794)
			(stroke
				(width 0.1)
				(type default)
			)
			(layer "F.Fab")
		)
		(fp_line
			(start -0.12065 -0.2794)
			(end 0.12065 -0.2794)
			(stroke
				(width 0.1)
				(type default)
			)
			(layer "F.Fab")
		)
		(fp_line
			(start -0.12065 0.2794)
			(end -0.12065 0.3048)
			(stroke
				(width 0.1)
				(type default)
			)
			(layer "F.Fab")
		)
		(fp_line
			(start -0.12065 0.3048)
			(end -0.67945 0.3048)
			(stroke
				(width 0.1)
				(type default)
			)
			(layer "F.Fab")
		)
		(fp_line
			(start 0.120396 0.2794)
			(end -0.12065 0.2794)
			(stroke
				(width 0.1)
				(type default)
			)
			(layer "F.Fab")
		)
		(fp_line
			(start 0.120396 0.3048)
			(end 0.120396 0.2794)
			(stroke
				(width 0.1)
				(type default)
			)
			(layer "F.Fab")
		)
		(fp_line
			(start 0.12065 -0.3048)
			(end 0.67945 -0.3048)
			(stroke
				(width 0.1)
				(type default)
			)
			(layer "F.Fab")
		)
		(fp_line
			(start 0.12065 -0.2794)
			(end 0.12065 -0.3048)
			(stroke
				(width 0.1)
				(type default)
			)
			(layer "F.Fab")
		)
		(fp_line
			(start 0.67945 -0.3048)
			(end 0.67945 0.3048)
			(stroke
				(width 0.1)
				(type default)
			)
			(layer "F.Fab")
		)
		(fp_line
			(start 0.67945 0.3048)
			(end 0.120396 0.3048)
			(stroke
				(width 0.1)
				(type default)
			)
			(layer "F.Fab")
		)
		(pad "1" smd circle
			(at -0.40005 0)
			(size 0 0)
			(layers "F.Cu" "F.Mask" "F.Paste")
			(net "RST_OCP_V3_2_BUF_N")
		)
		(pad "2" smd circle
			(at 0.40005 0)
			(size 0 0)
			(layers "F.Cu" "F.Mask" "F.Paste")
			(net "RST_PERST0_OCP_V3_2_N")
		)
	)
	(footprint ""
		(layer "F.Cu")
		(at 65.90411 -17.941544 180)
		(property "Reference" "C1829"
			(at 0 0 180)
			(layer "F.SilkS")
			(hide yes)
			(effects
				(font
					(size 1.27 1.27)
				)
			)
		)
		(property "Value" ""
			(at 0 0 180)
			(layer "F.Fab")
			(effects
				(font
					(size 1.27 1.27)
				)
			)
		)
		(duplicate_pad_numbers_are_jumpers no)
		(fp_line
			(start 1.524 0.762)
			(end -1.524 0.762)
			(stroke
				(width 0.1524)
				(type default)
			)
			(layer "F.SilkS")
		)
		(fp_line
			(start 1.524 -0.762)
			(end 1.524 0.762)
			(stroke
				(width 0.1524)
				(type default)
			)
			(layer "F.SilkS")
		)
		(fp_line
			(start -1.524 0.762)
			(end -1.524 -0.762)
			(stroke
				(width 0.1524)
				(type default)
			)
			(layer "F.SilkS")
		)
		(fp_line
			(start -1.524 -0.762)
			(end 1.524 -0.762)
			(stroke
				(width 0.1524)
				(type default)
			)
			(layer "F.SilkS")
		)
		(fp_line
			(start 1.1049 0.724916)
			(end 1.1049 -0.724916)
			(stroke
				(width 0.1)
				(type default)
			)
			(layer "F.Fab")
		)
		(fp_line
			(start 1.1049 -0.724916)
			(end -1.1049 -0.724916)
			(stroke
				(width 0.1)
				(type default)
			)
			(layer "F.Fab")
		)
		(fp_line
			(start -1.1049 0.724916)
			(end 1.1049 0.724916)
			(stroke
				(width 0.1)
				(type default)
			)
			(layer "F.Fab")
		)
		(fp_line
			(start -1.1049 -0.724916)
			(end -1.1049 0.724916)
			(stroke
				(width 0.1)
				(type default)
			)
			(layer "F.Fab")
		)
		(pad "1" smd rect
			(at -0.889 0)
			(size 1.016 1.27)
			(layers "F.Cu" "F.Mask" "F.Paste")
			(net "P12V_OCP_V3_2")
		)
		(pad "2" smd rect
			(at 0.889 0)
			(size 1.016 1.27)
			(layers "F.Cu" "F.Mask" "F.Paste")
			(net "GND")
		)
	)
)
